# S9S_MB_2U (Grand Teton) — schematic netlist excerpt (pin names and nets, part order shuffled) for the footprints in the layout excerpt that follows; sources: Cadence DE-HDL packaged netlist, KiCad conversion of 03242023_DA0F0TMBIJ0_F0T_Motherboard_J_brd_V01_OCP.brd

PR295  Q_RES  0 5% CHIP  pkg 0402LF  page 287 : A = PVCCIN_CPU1_VOS6 ; B = PVCCIN_CPU1
C90  Q_CAP  2.2UF 6.3V 20% X6S  pkg C0402  page 107 : A = P3V3_AUX ; B = GND
C328  Q_CAP  47UF 4V 20% X6S  pkg C0805  page 79 : A = PVCCIN_CPU1 ; B = GND

(kicad_pcb
	(version 20260206)
	(generator "pcbnew")
	(generator_version "10.0")
	(general
		(thickness 1.6)
		(legacy_teardrops no)
	)
	(paper "A4")
	(title_block
		(title "03242023_DA0F0TMBIJ0_F0T_Motherboard_J_brd_V01_OCP.brd")
		(comment 1 "Grand Teton / footprints 4287-4289 of 6105")
	)
	(layers
		(0 "F.Cu" signal "TOP")
		(4 "In1.Cu" signal "GND")
		(6 "In2.Cu" signal "IN1")
		(8 "In3.Cu" signal "GND1")
		(10 "In4.Cu" signal "IN2")
		(12 "In5.Cu" signal "GND2")
		(14 "In6.Cu" signal "IN3")
		(16 "In7.Cu" signal "GND3")
		(18 "In8.Cu" signal "VCC")
		(20 "In9.Cu" signal "VCC1")
		(22 "In10.Cu" signal "GND4")
		(24 "In11.Cu" signal "IN4")
		(26 "In12.Cu" signal "GND5")
		(28 "In13.Cu" signal "IN5")
		(30 "In14.Cu" signal "GND6")
		(32 "In15.Cu" signal "IN6")
		(34 "In16.Cu" signal "GND7")
		(2 "B.Cu" signal "BOTTOM")
		(9 "F.Adhes" user "F.Adhesive")
		(11 "B.Adhes" user "B.Adhesive")
		(13 "F.Paste" user "Package Geometry/Pastemask Top")
		(15 "B.Paste" user "Package Geometry/Pastemask Bottom")
		(5 "F.SilkS" user "Ref Des/Silkscreen Top")
		(7 "B.SilkS" user "Ref Des/Silkscreen Bottom")
		(1 "F.Mask" user "Board Geometry/Soldermask Top")
		(3 "B.Mask" user "Board Geometry/Soldermask Bottom")
		(17 "Dwgs.User" user "User.Drawings")
		(19 "Cmts.User" user "User.Comments")
		(21 "Eco1.User" user "User.Eco1")
		(23 "Eco2.User" user "User.Eco2")
		(25 "Edge.Cuts" user "Board Geometry/Outline")
		(27 "Margin" user)
		(31 "F.CrtYd" user "Package Geometry/Place Bound Top")
		(29 "B.CrtYd" user "Package Geometry/Place Bound Bottom")
		(35 "F.Fab" user "Ref Des/Assembly Top")
		(33 "B.Fab" user "Ref Des/Assembly Bottom")
	)
	(footprint ""
		(layer "B.Cu")
		(at 85.389466 -339.983572 -90)
		(property "Reference" "PR295"
			(at 0 0 90)
			(layer "B.SilkS")
			(hide yes)
			(effects
				(font
					(size 1.27 1.27)
				)
				(justify mirror)
			)
		)
		(property "Value" ""
			(at 0 0 90)
			(layer "B.Fab")
			(effects
				(font
					(size 1.27 1.27)
				)
				(justify mirror)
			)
		)
		(duplicate_pad_numbers_are_jumpers no)
		(fp_line
			(start -0.7874 0.4064)
			(end 0.7874 0.4064)
			(stroke
				(width 0.1524)
				(type default)
			)
			(layer "B.SilkS")
		)
		(fp_line
			(start 0.7874 0.4064)
			(end 0.7874 -0.4064)
			(stroke
				(width 0.1524)
				(type default)
			)
			(layer "B.SilkS")
		)
		(fp_line
			(start -0.7874 -0.4064)
			(end -0.7874 0.4064)
			(stroke
				(width 0.1524)
				(type default)
			)
			(layer "B.SilkS")
		)
		(fp_line
			(start 0.7874 -0.4064)
			(end -0.7874 -0.4064)
			(stroke
				(width 0.1524)
				(type default)
			)
			(layer "B.SilkS")
		)
		(fp_line
			(start -0.67945 0.3048)
			(end -0.120396 0.3048)
			(stroke
				(width 0.1)
				(type default)
			)
			(layer "B.Fab")
		)
		(fp_line
			(start -0.120396 0.3048)
			(end -0.120396 0.2794)
			(stroke
				(width 0.1)
				(type default)
			)
			(layer "B.Fab")
		)
		(fp_line
			(start 0.12065 0.3048)
			(end 0.67945 0.3048)
			(stroke
				(width 0.1)
				(type default)
			)
			(layer "B.Fab")
		)
		(fp_line
			(start 0.67945 0.3048)
			(end 0.67945 -0.305054)
			(stroke
				(width 0.1)
				(type default)
			)
			(layer "B.Fab")
		)
		(fp_line
			(start -0.120396 0.2794)
			(end 0.12065 0.2794)
			(stroke
				(width 0.1)
				(type default)
			)
			(layer "B.Fab")
		)
		(fp_line
			(start 0.12065 0.2794)
			(end 0.12065 0.3048)
			(stroke
				(width 0.1)
				(type default)
			)
			(layer "B.Fab")
		)
		(fp_line
			(start -0.12065 -0.2794)
			(end -0.12065 -0.3048)
			(stroke
				(width 0.1)
				(type default)
			)
			(layer "B.Fab")
		)
		(fp_line
			(start 0.12065 -0.2794)
			(end -0.12065 -0.2794)
			(stroke
				(width 0.1)
				(type default)
			)
			(layer "B.Fab")
		)
		(fp_line
			(start -0.67945 -0.3048)
			(end -0.67945 0.3048)
			(stroke
				(width 0.1)
				(type default)
			)
			(layer "B.Fab")
		)
		(fp_line
			(start -0.12065 -0.3048)
			(end -0.67945 -0.3048)
			(stroke
				(width 0.1)
				(type default)
			)
			(layer "B.Fab")
		)
		(fp_line
			(start 0.12065 -0.305054)
			(end 0.12065 -0.2794)
			(stroke
				(width 0.1)
				(type default)
			)
			(layer "B.Fab")
		)
		(fp_line
			(start 0.67945 -0.305054)
			(end 0.12065 -0.305054)
			(stroke
				(width 0.1)
				(type default)
			)
			(layer "B.Fab")
		)
		(pad "1" smd circle
			(at 0.40005 0 90)
			(size 0 0)
			(layers "B.Cu" "B.Mask" "B.Paste")
			(net "PVCCIN_CPU1_VOS6")
		)
		(pad "2" smd circle
			(at -0.40005 0 90)
			(size 0 0)
			(layers "B.Cu" "B.Mask" "B.Paste")
			(net "PVCCIN_CPU1")
		)
	)
	(footprint ""
		(layer "B.Cu")
		(at 158.697168 -319.363344)
		(property "Reference" "C90"
			(at 0 0 0)
			(layer "B.SilkS")
			(hide yes)
			(effects
				(font
					(size 1.27 1.27)
				)
				(justify mirror)
			)
		)
		(property "Value" ""
			(at 0 0 0)
			(layer "B.Fab")
			(effects
				(font
					(size 1.27 1.27)
				)
				(justify mirror)
			)
		)
		(duplicate_pad_numbers_are_jumpers no)
		(fp_line
			(start -0.7874 -0.4064)
			(end -0.7874 0.4064)
			(stroke
				(width 0.1524)
				(type default)
			)
			(layer "B.SilkS")
		)
		(fp_line
			(start -0.7874 0.4064)
			(end 0.7874 0.4064)
			(stroke
				(width 0.1524)
				(type default)
			)
			(layer "B.SilkS")
		)
		(fp_line
			(start 0.7874 -0.4064)
			(end -0.7874 -0.4064)
			(stroke
				(width 0.1524)
				(type default)
			)
			(layer "B.SilkS")
		)
		(fp_line
			(start 0.7874 0.4064)
			(end 0.7874 -0.4064)
			(stroke
				(width 0.1524)
				(type default)
			)
			(layer "B.SilkS")
		)
		(fp_line
			(start -0.67945 -0.3048)
			(end -0.67945 0.3048)
			(stroke
				(width 0.1)
				(type default)
			)
			(layer "B.Fab")
		)
		(fp_line
			(start -0.67945 0.3048)
			(end -0.120396 0.3048)
			(stroke
				(width 0.1)
				(type default)
			)
			(layer "B.Fab")
		)
		(fp_line
			(start -0.12065 -0.3048)
			(end -0.67945 -0.3048)
			(stroke
				(width 0.1)
				(type default)
			)
			(layer "B.Fab")
		)
		(fp_line
			(start -0.12065 -0.2794)
			(end -0.12065 -0.3048)
			(stroke
				(width 0.1)
				(type default)
			)
			(layer "B.Fab")
		)
		(fp_line
			(start -0.120396 0.2794)
			(end 0.12065 0.2794)
			(stroke
				(width 0.1)
				(type default)
			)
			(layer "B.Fab")
		)
		(fp_line
			(start -0.120396 0.3048)
			(end -0.120396 0.2794)
			(stroke
				(width 0.1)
				(type default)
			)
			(layer "B.Fab")
		)
		(fp_line
			(start 0.12065 -0.305054)
			(end 0.12065 -0.2794)
			(stroke
				(width 0.1)
				(type default)
			)
			(layer "B.Fab")
		)
		(fp_line
			(start 0.12065 -0.2794)
			(end -0.12065 -0.2794)
			(stroke
				(width 0.1)
				(type default)
			)
			(layer "B.Fab")
		)
		(fp_line
			(start 0.12065 0.2794)
			(end 0.12065 0.3048)
			(stroke
				(width 0.1)
				(type default)
			)
			(layer "B.Fab")
		)
		(fp_line
			(start 0.12065 0.3048)
			(end 0.67945 0.3048)
			(stroke
				(width 0.1)
				(type default)
			)
			(layer "B.Fab")
		)
		(fp_line
			(start 0.67945 -0.305054)
			(end 0.12065 -0.305054)
			(stroke
				(width 0.1)
				(type default)
			)
			(layer "B.Fab")
		)
		(fp_line
			(start 0.67945 0.3048)
			(end 0.67945 -0.305054)
			(stroke
				(width 0.1)
				(type default)
			)
			(layer "B.Fab")
		)
		(pad "1" smd circle
			(at 0.40005 0 180)
			(size 0 0)
			(layers "B.Cu" "B.Mask" "B.Paste")
			(net "P3V3_AUX")
		)
		(pad "2" smd circle
			(at -0.40005 0 180)
			(size 0 0)
			(layers "B.Cu" "B.Mask" "B.Paste")
			(net "GND")
		)
	)
	(footprint ""
		(layer "B.Cu")
		(at 108.845604 -294.01008 180)
		(property "Reference" "C328"
			(at 0 0 0)
			(layer "B.SilkS")
			(hide yes)
			(effects
				(font
					(size 1.27 1.27)
				)
				(justify mirror)
			)
		)
		(property "Value" ""
			(at 0 0 0)
			(layer "B.Fab")
			(effects
				(font
					(size 1.27 1.27)
				)
				(justify mirror)
			)
		)
		(duplicate_pad_numbers_are_jumpers no)
		(fp_line
			(start 1.524 0.762)
			(end 1.524 -0.762)
			(stroke
				(width 0.1524)
				(type default)
			)
			(layer "B.SilkS")
		)
		(fp_line
			(start 1.524 -0.762)
			(end -1.524 -0.762)
			(stroke
				(width 0.1524)
				(type default)
			)
			(layer "B.SilkS")
		)
		(fp_line
			(start -1.524 0.762)
			(end 1.524 0.762)
			(stroke
				(width 0.1524)
				(type default)
			)
			(layer "B.SilkS")
		)
		(fp_line
			(start -1.524 -0.762)
			(end -1.524 0.762)
			(stroke
				(width 0.1524)
				(type default)
			)
			(layer "B.SilkS")
		)
		(fp_line
			(start 1.1049 0.724916)
			(end -1.1049 0.724916)
			(stroke
				(width 0.1)
				(type default)
			)
			(layer "B.Fab")
		)
		(fp_line
			(start 1.1049 -0.724916)
			(end 1.1049 0.724916)
			(stroke
				(width 0.1)
				(type default)
			)
			(layer "B.Fab")
		)
		(fp_line
			(start -1.1049 0.724916)
			(end -1.1049 -0.724916)
			(stroke
				(width 0.1)
				(type default)
			)
			(layer "B.Fab")
		)
		(fp_line
			(start -1.1049 -0.724916)
			(end 1.1049 -0.724916)
			(stroke
				(width 0.1)
				(type default)
			)
			(layer "B.Fab")
		)
		(pad "1" smd rect
			(at 0.889 0 180)
			(size 1.016 1.27)
			(layers "B.Cu" "B.Mask" "B.Paste")
			(net "PVCCIN_CPU1")
		)
		(pad "2" smd rect
			(at -0.889 0 180)
			(size 1.016 1.27)
			(layers "B.Cu" "B.Mask" "B.Paste")
			(net "GND")
		)
	)
)
